(kicad_pcb
	(version 20260206)
	(generator "pcbnew")
	(generator_version "10.0")
	(general
		(thickness 1.6)
		(legacy_teardrops no)
	)
	(paper "A4")
	(title_block
		(title "Bryce Canyon_IOM_M2_16342-2_OCP.brd")
		(comment 1 "Bryce Canyon / footprints 456-462 of 1146")
	)
	(layers
		(0 "F.Cu" signal "TOP")
		(4 "In1.Cu" signal "L2GND")
		(6 "In2.Cu" signal "L3")
		(8 "In3.Cu" signal "L4VCC")
		(10 "In4.Cu" signal "L5VCC")
		(12 "In5.Cu" signal "L6")
		(14 "In6.Cu" signal "L7GND")
		(2 "B.Cu" signal "BOTTOM")
		(9 "F.Adhes" user "F.Adhesive")
		(11 "B.Adhes" user "B.Adhesive")
		(13 "F.Paste" user "Package Geometry/Pastemask Top")
		(15 "B.Paste" user "Package Geometry/Pastemask Bottom")
		(5 "F.SilkS" user "Ref Des/Silkscreen Top")
		(7 "B.SilkS" user "Ref Des/Silkscreen Bottom")
		(1 "F.Mask" user "Board Geometry/Soldermask Top")
		(3 "B.Mask" user "Board Geometry/Soldermask Bottom")
		(17 "Dwgs.User" user "User.Drawings")
		(19 "Cmts.User" user "User.Comments")
		(21 "Eco1.User" user "User.Eco1")
		(23 "Eco2.User" user "User.Eco2")
		(25 "Edge.Cuts" user "Board Geometry/Outline")
		(27 "Margin" user)
		(31 "F.CrtYd" user "Package Geometry/Place Bound Top")
		(29 "B.CrtYd" user "Package Geometry/Place Bound Bottom")
		(35 "F.Fab" user "Ref Des/Assembly Top")
		(33 "B.Fab" user "Ref Des/Assembly Bottom")
	)
	(footprint ""
		(layer "F.Cu")
		(at 94.488 -17.8562)
		(property "Reference" "D19"
			(at 0 0 0)
			(layer "F.SilkS")
			(hide yes)
			(effects
				(font
					(size 1.27 1.27)
				)
			)
		)
		(property "Value" "PESD5V0F1BL-GP"
			(at 1.8923 -1.5621 0)
			(unlocked yes)
			(layer "F.Fab")
			(hide yes)
			(effects
				(font
					(size 1.016 1.016)
					(thickness 0.1524)
				)
			)
		)
		(property "Device Type" "SOD882-10D6-1H20"
			(at 1.8923 -3.0861 0)
			(unlocked yes)
			(layer "F.Fab")
			(hide yes)
			(effects
				(font
					(size 1.016 1.016)
					(thickness 0.1524)
				)
			)
		)
		(duplicate_pad_numbers_are_jumpers no)
		(fp_line
			(start -0.3048 -0.9271)
			(end 0.3048 -0.9271)
			(stroke
				(width 0.254)
				(type default)
			)
			(layer "F.SilkS")
		)
		(fp_rect
			(start -0.2921 0.4953)
			(end 0.2921 -0.4953)
			(stroke
				(width 0)
				(type default)
			)
			(fill no)
			(layer "F.CrtYd")
		)
		(fp_poly
			(pts
				(xy -0.4318 0.8001) (xy -0.4318 -0.266192) (xy -0.2921 -0.266192) (xy -0.2921 0.4953) (xy 0.2921 0.4953)
				(xy 0.2921 -0.4953) (xy -0.2921 -0.4953) (xy -0.2921 -0.2667) (xy -0.4318 -0.2667) (xy -0.4318 -0.8001)
				(xy 0.4318 -0.8001) (xy 0.4318 0.8001)
			)
			(stroke
				(width 0)
				(type default)
			)
			(fill no)
			(layer "F.CrtYd")
		)
		(fp_rect
			(start -0.4318 0.8001)
			(end 0.4318 -0.8001)
			(stroke
				(width 0)
				(type default)
			)
			(fill no)
			(layer "F.Fab")
		)
		(pad "1" smd custom
			(at 0 -0.4445)
			(size 0.1143 0.1143)
			(layers "F.Cu" "F.Mask" "F.Paste")
			(net "GND")
			(options
				(clearance outline)
				(anchor circle)
			)
			(primitives
				(gr_poly
					(pts
						(arc
							(start -0.2032 0.2286)
							(mid -0.275042 0.198842)
							(end -0.3048 0.127)
						)
						(arc
							(start -0.3048 -0.127)
							(mid -0.275042 -0.198842)
							(end -0.2032 -0.2286)
						)
						(arc
							(start 0.2032 -0.2286)
							(mid 0.275042 -0.198842)
							(end 0.3048 -0.127)
						)
						(arc
							(start 0.3048 0.127)
							(mid 0.275042 0.198842)
							(end 0.2032 0.2286)
						)
					)
					(width 0)
					(fill yes)
				)
			)
		)
		(pad "2" smd custom
			(at 0 0.4445)
			(size 0.1143 0.1143)
			(layers "F.Cu" "F.Mask" "F.Paste")
			(net "USB_P1_F_DN1")
			(options
				(clearance outline)
				(anchor circle)
			)
			(primitives
				(gr_poly
					(pts
						(arc
							(start 0.2032 -0.2286)
							(mid 0.275042 -0.198842)
							(end 0.3048 -0.127)
						)
						(arc
							(start 0.3048 0.127)
							(mid 0.275042 0.198842)
							(end 0.2032 0.2286)
						)
						(arc
							(start -0.2032 0.2286)
							(mid -0.275042 0.198842)
							(end -0.3048 0.127)
						)
						(arc
							(start -0.3048 -0.127)
							(mid -0.275042 -0.198842)
							(end -0.2032 -0.2286)
						)
					)
					(width 0)
					(fill yes)
				)
			)
		)
	)
	(footprint ""
		(layer "F.Cu")
		(at 60.494672 -134.434326)
		(property "Reference" "TP207"
			(at 0 0 0)
			(layer "F.SilkS")
			(hide yes)
			(effects
				(font
					(size 1.27 1.27)
				)
			)
		)
		(property "Value" "TPAD28-2-GP"
			(at -0.0127 -1.6637 0)
			(unlocked yes)
			(layer "F.Fab")
			(hide yes)
			(effects
				(font
					(size 1.016 1.016)
					(thickness 0.1524)
				)
			)
		)
		(property "Device Type" "TPAD28"
			(at -0.0127 -3.1877 0)
			(unlocked yes)
			(layer "F.Fab")
			(hide yes)
			(effects
				(font
					(size 1.016 1.016)
					(thickness 0.1524)
				)
			)
		)
		(duplicate_pad_numbers_are_jumpers no)
		(fp_poly
			(pts
				(arc
					(start 0.3556 0)
					(mid -0.3556 0)
					(end 0.3556 0)
				)
			)
			(stroke
				(width 0)
				(type default)
			)
			(fill no)
			(layer "F.CrtYd")
		)
		(fp_poly
			(pts
				(arc
					(start 0.6096 0)
					(mid -0.6096 0)
					(end 0.6096 0)
				)
			)
			(stroke
				(width 0)
				(type default)
			)
			(fill no)
			(layer "F.Fab")
		)
		(pad "1" smd circle
			(at 0 0)
			(size 0.7112 0.7112)
			(layers "F.Cu" "F.Mask" "F.Paste")
			(net "TP_BMC_EXT2_LED_B")
		)
	)
	(footprint ""
		(layer "F.Cu")
		(at 124.8156 -5.5372 -90)
		(property "Reference" "R712"
			(at 0 0 270)
			(layer "F.SilkS")
			(hide yes)
			(effects
				(font
					(size 1.27 1.27)
				)
			)
		)
		(property "Value" "0R2J-2-GP"
			(at 0.064008 -3.993896 270)
			(unlocked yes)
			(layer "F.Fab")
			(hide yes)
			(effects
				(font
					(size 1.016 1.016)
					(thickness 0.1524)
				)
			)
		)
		(property "Device Type" "R402H16"
			(at 0.064008 -5.517896 270)
			(unlocked yes)
			(layer "F.Fab")
			(hide yes)
			(effects
				(font
					(size 1.016 1.016)
					(thickness 0.1524)
				)
			)
		)
		(duplicate_pad_numbers_are_jumpers no)
		(fp_line
			(start -0.508 -0.9398)
			(end -0.508 0.9398)
			(stroke
				(width 0.1524)
				(type default)
			)
			(layer "F.SilkS")
		)
		(fp_line
			(start 0.508 -0.9398)
			(end -0.508 -0.9398)
			(stroke
				(width 0.1524)
				(type default)
			)
			(layer "F.SilkS")
		)
		(fp_rect
			(start -0.508 0.9398)
			(end 0.508 -0.9398)
			(stroke
				(width 0)
				(type default)
			)
			(fill no)
			(layer "F.CrtYd")
		)
		(fp_rect
			(start -0.508 0.9398)
			(end 0.508 -0.9398)
			(stroke
				(width 0)
				(type default)
			)
			(fill no)
			(layer "F.Fab")
		)
		(pad "1" smd custom
			(at 0 -0.4445 270)
			(size 0.1397 0.1397)
			(layers "F.Cu" "F.Mask" "F.Paste")
			(net "I2C_IOM_SDA")
			(options
				(clearance outline)
				(anchor circle)
			)
			(primitives
				(gr_poly
					(pts
						(arc
							(start -0.1778 -0.2794)
							(mid -0.249642 -0.249642)
							(end -0.2794 -0.1778)
						)
						(arc
							(start -0.2794 0.1778)
							(mid -0.249642 0.249642)
							(end -0.1778 0.2794)
						)
						(arc
							(start 0.1778 0.2794)
							(mid 0.249642 0.249642)
							(end 0.2794 0.1778)
						)
						(arc
							(start 0.2794 -0.1778)
							(mid 0.249642 -0.249642)
							(end 0.1778 -0.2794)
						)
					)
					(width 0)
					(fill yes)
				)
			)
		)
		(pad "2" smd custom
			(at 0 0.4445 270)
			(size 0.1397 0.1397)
			(layers "F.Cu" "F.Mask" "F.Paste")
			(net "HSW_SDA")
			(options
				(clearance outline)
				(anchor circle)
			)
			(primitives
				(gr_poly
					(pts
						(arc
							(start -0.1778 -0.2794)
							(mid -0.249642 -0.249642)
							(end -0.2794 -0.1778)
						)
						(arc
							(start -0.2794 0.1778)
							(mid -0.249642 0.249642)
							(end -0.1778 0.2794)
						)
						(arc
							(start 0.1778 0.2794)
							(mid 0.249642 0.249642)
							(end 0.2794 0.1778)
						)
						(arc
							(start 0.2794 -0.1778)
							(mid 0.249642 -0.249642)
							(end 0.1778 -0.2794)
						)
					)
					(width 0)
					(fill yes)
				)
			)
		)
	)
	(footprint ""
		(layer "F.Cu")
		(at 83.4644 -168.1734)
		(property "Reference" "Q11"
			(at 0 0 0)
			(layer "F.SilkS")
			(hide yes)
			(effects
				(font
					(size 1.27 1.27)
				)
			)
		)
		(property "Value" "2N7002K-1-GP"
			(at 0.127 -8.9662 0)
			(unlocked yes)
			(layer "F.Fab")
			(hide yes)
			(effects
				(font
					(size 1.016 1.016)
					(thickness 0.1524)
				)
			)
		)
		(property "Device Type" "SOT23DGS2D4H44"
			(at 0.127 -10.4902 0)
			(unlocked yes)
			(layer "F.Fab")
			(hide yes)
			(effects
				(font
					(size 1.016 1.016)
					(thickness 0.1524)
				)
			)
		)
		(duplicate_pad_numbers_are_jumpers no)
		(fp_line
			(start -1.651 -1.778)
			(end -1.651 1.778)
			(stroke
				(width 0.1524)
				(type default)
			)
			(layer "F.SilkS")
		)
		(fp_line
			(start -1.651 1.778)
			(end 1.651 1.778)
			(stroke
				(width 0.1524)
				(type default)
			)
			(layer "F.SilkS")
		)
		(fp_line
			(start 1.651 -1.778)
			(end -1.651 -1.778)
			(stroke
				(width 0.1524)
				(type default)
			)
			(layer "F.SilkS")
		)
		(fp_line
			(start 1.651 1.778)
			(end 1.651 -1.778)
			(stroke
				(width 0.1524)
				(type default)
			)
			(layer "F.SilkS")
		)
		(fp_poly
			(pts
				(xy -1.778 1.8796) (xy -1.778 -1.8796) (xy 1.778 -1.8796) (xy 1.778 1.8796)
			)
			(stroke
				(width 0)
				(type default)
			)
			(fill no)
			(layer "F.CrtYd")
		)
		(fp_poly
			(pts
				(xy -1.778 1.8796) (xy -1.778 -1.8796) (xy 1.778 -1.8796) (xy 1.778 1.8796)
			)
			(stroke
				(width 0)
				(type default)
			)
			(fill no)
			(layer "F.Fab")
		)
		(pad "D" smd custom
			(at 0 -0.9525)
			(size 0.1905 0.1905)
			(layers "F.Cu" "F.Mask" "F.Paste")
			(net "P1V15_STBY_PG_G")
			(options
				(clearance outline)
				(anchor circle)
			)
			(primitives
				(gr_poly
					(pts
						(arc
							(start -0.1778 0.5715)
							(mid -0.321484 0.511984)
							(end -0.381 0.3683)
						)
						(arc
							(start -0.381 -0.3683)
							(mid -0.321484 -0.511984)
							(end -0.1778 -0.5715)
						)
						(arc
							(start 0.1778 -0.5715)
							(mid 0.321484 -0.511984)
							(end 0.381 -0.3683)
						)
						(arc
							(start 0.381 0.3683)
							(mid 0.321484 0.511984)
							(end 0.1778 0.5715)
						)
					)
					(width 0)
					(fill yes)
				)
			)
		)
		(pad "G" smd custom
			(at -0.98425 0.9525)
			(size 0.1905 0.1905)
			(layers "F.Cu" "F.Mask" "F.Paste")
			(net "P1V15_STBY_PG")
			(options
				(clearance outline)
				(anchor circle)
			)
			(primitives
				(gr_poly
					(pts
						(arc
							(start -0.1778 0.5715)
							(mid -0.321484 0.511984)
							(end -0.381 0.3683)
						)
						(arc
							(start -0.381 -0.3683)
							(mid -0.321484 -0.511984)
							(end -0.1778 -0.5715)
						)
						(arc
							(start 0.1778 -0.5715)
							(mid 0.321484 -0.511984)
							(end 0.381 -0.3683)
						)
						(arc
							(start 0.381 0.3683)
							(mid 0.321484 0.511984)
							(end 0.1778 0.5715)
						)
					)
					(width 0)
					(fill yes)
				)
			)
		)
		(pad "S" smd custom
			(at 0.98425 0.9525)
			(size 0.1905 0.1905)
			(layers "F.Cu" "F.Mask" "F.Paste")
			(net "GND")
			(options
				(clearance outline)
				(anchor circle)
			)
			(primitives
				(gr_poly
					(pts
						(arc
							(start -0.1778 0.5715)
							(mid -0.321484 0.511984)
							(end -0.381 0.3683)
						)
						(arc
							(start -0.381 -0.3683)
							(mid -0.321484 -0.511984)
							(end -0.1778 -0.5715)
						)
						(arc
							(start 0.1778 -0.5715)
							(mid 0.321484 -0.511984)
							(end 0.381 -0.3683)
						)
						(arc
							(start 0.381 0.3683)
							(mid 0.321484 0.511984)
							(end 0.1778 0.5715)
						)
					)
					(width 0)
					(fill yes)
				)
			)
		)
	)
	(footprint ""
		(layer "F.Cu")
		(at 218.52128 -103.040688 90)
		(property "Reference" "C645"
			(at 0 0 90)
			(layer "F.SilkS")
			(hide yes)
			(effects
				(font
					(size 1.27 1.27)
				)
			)
		)
		(property "Value" "SC1U16V3KX-5GP"
			(at 0 -2.8194 90)
			(unlocked yes)
			(layer "F.Fab")
			(hide yes)
			(effects
				(font
					(size 1.016 1.016)
					(thickness 0.1524)
				)
			)
		)
		(property "Device Type" "C603H36"
			(at 0 -4.3434 90)
			(unlocked yes)
			(layer "F.Fab")
			(hide yes)
			(effects
				(font
					(size 1.016 1.016)
					(thickness 0.1524)
				)
			)
		)
		(duplicate_pad_numbers_are_jumpers no)
		(fp_line
			(start 0.508 0)
			(end -0.508 0)
			(stroke
				(width 0.2032)
				(type default)
			)
			(layer "F.SilkS")
		)
		(fp_rect
			(start -0.5842 1.3335)
			(end 0.5842 -1.3335)
			(stroke
				(width 0)
				(type default)
			)
			(fill no)
			(layer "F.CrtYd")
		)
		(fp_rect
			(start -0.5842 1.3335)
			(end 0.5842 -1.3335)
			(stroke
				(width 0)
				(type default)
			)
			(fill no)
			(layer "F.Fab")
		)
		(pad "1" smd custom
			(at 0 -0.762 90)
			(size 0.2159 0.2159)
			(layers "F.Cu" "F.Mask" "F.Paste")
			(net "GND")
			(options
				(clearance outline)
				(anchor circle)
			)
			(primitives
				(gr_poly
					(pts
						(arc
							(start -0.3302 -0.4318)
							(mid -0.402042 -0.402042)
							(end -0.4318 -0.3302)
						)
						(arc
							(start -0.4318 0.3302)
							(mid -0.402042 0.402042)
							(end -0.3302 0.4318)
						)
						(arc
							(start 0.3302 0.4318)
							(mid 0.402042 0.402042)
							(end 0.4318 0.3302)
						)
						(arc
							(start 0.4318 -0.3302)
							(mid 0.402042 -0.402042)
							(end 0.3302 -0.4318)
						)
					)
					(width 0)
					(fill yes)
				)
			)
		)
		(pad "2" smd custom
			(at 0 0.762 90)
			(size 0.2159 0.2159)
			(layers "F.Cu" "F.Mask" "F.Paste")
			(net "P3V3_M2_VREG")
			(options
				(clearance outline)
				(anchor circle)
			)
			(primitives
				(gr_poly
					(pts
						(arc
							(start -0.3302 -0.4318)
							(mid -0.402042 -0.402042)
							(end -0.4318 -0.3302)
						)
						(arc
							(start -0.4318 0.3302)
							(mid -0.402042 0.402042)
							(end -0.3302 0.4318)
						)
						(arc
							(start 0.3302 0.4318)
							(mid 0.402042 0.402042)
							(end 0.4318 0.3302)
						)
						(arc
							(start 0.4318 -0.3302)
							(mid 0.402042 -0.402042)
							(end 0.3302 -0.4318)
						)
					)
					(width 0)
					(fill yes)
				)
			)
		)
	)
	(footprint ""
		(layer "F.Cu")
		(at 61.8998 -140.6652)
		(property "Reference" "R271"
			(at 0 0 0)
			(layer "F.SilkS")
			(hide yes)
			(effects
				(font
					(size 1.27 1.27)
				)
			)
		)
		(property "Value" "4K7R2F-GP"
			(at 0.064008 -3.993896 0)
			(unlocked yes)
			(layer "F.Fab")
			(hide yes)
			(effects
				(font
					(size 1.016 1.016)
					(thickness 0.1524)
				)
			)
		)
		(property "Device Type" "R402H16"
			(at 0.064008 -5.517896 0)
			(unlocked yes)
			(layer "F.Fab")
			(hide yes)
			(effects
				(font
					(size 1.016 1.016)
					(thickness 0.1524)
				)
			)
		)
		(duplicate_pad_numbers_are_jumpers no)
		(fp_line
			(start -0.508 -0.9398)
			(end -0.508 0.9398)
			(stroke
				(width 0.1524)
				(type default)
			)
			(layer "F.SilkS")
		)
		(fp_line
			(start 0.508 -0.9398)
			(end -0.508 -0.9398)
			(stroke
				(width 0.1524)
				(type default)
			)
			(layer "F.SilkS")
		)
		(fp_rect
			(start -0.508 0.9398)
			(end 0.508 -0.9398)
			(stroke
				(width 0)
				(type default)
			)
			(fill no)
			(layer "F.CrtYd")
		)
		(fp_rect
			(start -0.508 0.9398)
			(end 0.508 -0.9398)
			(stroke
				(width 0)
				(type default)
			)
			(fill no)
			(layer "F.Fab")
		)
		(pad "1" smd custom
			(at 0 -0.4445)
			(size 0.1397 0.1397)
			(layers "F.Cu" "F.Mask" "F.Paste")
			(net "BMC_TO_EXP_RESET_OUT")
			(options
				(clearance outline)
				(anchor circle)
			)
			(primitives
				(gr_poly
					(pts
						(arc
							(start -0.1778 -0.2794)
							(mid -0.249642 -0.249642)
							(end -0.2794 -0.1778)
						)
						(arc
							(start -0.2794 0.1778)
							(mid -0.249642 0.249642)
							(end -0.1778 0.2794)
						)
						(arc
							(start 0.1778 0.2794)
							(mid 0.249642 0.249642)
							(end 0.2794 0.1778)
						)
						(arc
							(start 0.2794 -0.1778)
							(mid 0.249642 -0.249642)
							(end 0.1778 -0.2794)
						)
					)
					(width 0)
					(fill yes)
				)
			)
		)
		(pad "2" smd custom
			(at 0 0.4445)
			(size 0.1397 0.1397)
			(layers "F.Cu" "F.Mask" "F.Paste")
			(net "P3V3_STBY")
			(options
				(clearance outline)
				(anchor circle)
			)
			(primitives
				(gr_poly
					(pts
						(arc
							(start -0.1778 -0.2794)
							(mid -0.249642 -0.249642)
							(end -0.2794 -0.1778)
						)
						(arc
							(start -0.2794 0.1778)
							(mid -0.249642 0.249642)
							(end -0.1778 0.2794)
						)
						(arc
							(start 0.1778 0.2794)
							(mid 0.249642 0.249642)
							(end 0.2794 0.1778)
						)
						(arc
							(start 0.2794 -0.1778)
							(mid 0.249642 -0.249642)
							(end 0.1778 -0.2794)
						)
					)
					(width 0)
					(fill yes)
				)
			)
		)
	)
	(footprint ""
		(layer "F.Cu")
		(at 225.880168 -55.07609 90)
		(property "Reference" "C155"
			(at 0 0 90)
			(layer "F.SilkS")
			(hide yes)
			(effects
				(font
					(size 1.27 1.27)
				)
			)
		)
		(property "Value" "SC10U16V5KX-7-GP-U"
			(at -0.0762 -6.1214 90)
			(unlocked yes)
			(layer "F.Fab")
			(hide yes)
			(effects
				(font
					(size 1.016 1.016)
					(thickness 0.1524)
				)
			)
		)
		(property "Device Type" "C805H58"
			(at -0.0762 -8.1534 90)
			(unlocked yes)
			(layer "F.Fab")
			(hide yes)
			(effects
				(font
					(size 1.016 1.016)
					(thickness 0.1524)
				)
			)
		)
		(duplicate_pad_numbers_are_jumpers no)
		(fp_line
			(start 0.635 0)
			(end -0.635 0)
			(stroke
				(width 0.508)
				(type default)
			)
			(layer "F.SilkS")
		)
		(fp_rect
			(start -0.9652 1.778)
			(end 0.9652 -1.778)
			(stroke
				(width 0)
				(type default)
			)
			(fill no)
			(layer "F.CrtYd")
		)
		(fp_poly
			(pts
				(xy -0.9652 -1.778) (xy 0.9652 -1.778) (xy 0.9652 1.778) (xy -0.9652 1.778)
			)
			(stroke
				(width 0)
				(type default)
			)
			(fill no)
			(layer "F.Fab")
		)
		(pad "1" smd rect
			(at 0 -0.9652 90)
			(size 1.397 1.143)
			(layers "F.Cu" "F.Mask" "F.Paste")
			(net "P12V_STBY_VIN_PU1")
		)
		(pad "2" smd rect
			(at 0 0.9652 90)
			(size 1.397 1.143)
			(layers "F.Cu" "F.Mask" "F.Paste")
			(net "GND")
		)
	)
)
